(kicad_pcb
	(version 20260206)
	(generator "pcbnew")
	(generator_version "10.0")
	(general
		(thickness 1.6)
		(legacy_teardrops no)
	)
	(paper "A4")
	(title_block
		(title "Wiwynn_Tioga_Pass_MB.brd")
		(comment 1 "Tioga Pass / footprints 1024-1030 of 4770")
	)
	(layers
		(0 "F.Cu" signal "TOP")
		(4 "In1.Cu" signal "L2GND")
		(6 "In2.Cu" signal "L3")
		(8 "In3.Cu" signal "L4GND")
		(10 "In4.Cu" signal "L5")
		(12 "In5.Cu" signal "L6GND")
		(14 "In6.Cu" signal "L7VCC")
		(16 "In7.Cu" signal "L8VCC")
		(18 "In8.Cu" signal "L9GND")
		(20 "In9.Cu" signal "L10")
		(22 "In10.Cu" signal "L11GND")
		(24 "In11.Cu" signal "L12")
		(26 "In12.Cu" signal "L13GND")
		(2 "B.Cu" signal "BOTTOM")
		(9 "F.Adhes" user "F.Adhesive")
		(11 "B.Adhes" user "B.Adhesive")
		(13 "F.Paste" user "Package Geometry/Pastemask Top")
		(15 "B.Paste" user "Package Geometry/Pastemask Bottom")
		(5 "F.SilkS" user "Ref Des/Silkscreen Top")
		(7 "B.SilkS" user "Ref Des/Silkscreen Bottom")
		(1 "F.Mask" user "Board Geometry/Soldermask Top")
		(3 "B.Mask" user "Board Geometry/Soldermask Bottom")
		(17 "Dwgs.User" user "User.Drawings")
		(19 "Cmts.User" user "User.Comments")
		(21 "Eco1.User" user "User.Eco1")
		(23 "Eco2.User" user "User.Eco2")
		(25 "Edge.Cuts" user "Board Geometry/Outline")
		(27 "Margin" user)
		(31 "F.CrtYd" user "Package Geometry/Place Bound Top")
		(29 "B.CrtYd" user "Package Geometry/Place Bound Bottom")
		(35 "F.Fab" user "Ref Des/Assembly Top")
		(33 "B.Fab" user "Ref Des/Assembly Bottom")
	)
	(footprint ""
		(layer "F.Cu")
		(at 454.279 -157.607)
		(property "Reference" "Q9A1"
			(at 2.28854 2.19075 180)
			(unlocked yes)
			(layer "F.SilkS")
			(effects
				(font
					(size 0.7874 0.5842)
					(thickness 0.1524)
				)
				(justify left)
			)
		)
		(property "Value" ""
			(at 0 0 0)
			(layer "F.Fab")
			(effects
				(font
					(size 1.27 1.27)
				)
			)
		)
		(duplicate_pad_numbers_are_jumpers no)
		(fp_circle
			(center -0.848614 -0.6477)
			(end -0.721614 -0.6477)
			(stroke
				(width 0.254)
				(type default)
			)
			(fill no)
			(layer "F.SilkS")
		)
		(fp_poly
			(pts
				(xy 0.21463 -0.450088) (xy 1.56337 -0.450088) (xy 1.56337 1.75006) (xy 0.21463 1.75006)
			)
			(stroke
				(width 0)
				(type default)
			)
			(fill no)
			(layer "F.CrtYd")
		)
		(fp_line
			(start 0.21463 -0.450088)
			(end 1.56337 -0.450088)
			(stroke
				(width 0.1)
				(type default)
			)
			(layer "F.Fab")
		)
		(fp_line
			(start 0.21463 1.75006)
			(end 0.21463 -0.450088)
			(stroke
				(width 0.1)
				(type default)
			)
			(layer "F.Fab")
		)
		(fp_line
			(start 1.56337 -0.450088)
			(end 1.56337 1.75006)
			(stroke
				(width 0.1)
				(type default)
			)
			(layer "F.Fab")
		)
		(fp_line
			(start 1.56337 1.75006)
			(end 0.21463 1.75006)
			(stroke
				(width 0.1)
				(type default)
			)
			(layer "F.Fab")
		)
		(fp_circle
			(center -0.848614 -0.6477)
			(end -0.721614 -0.6477)
			(stroke
				(width 0.254)
				(type default)
			)
			(fill no)
			(layer "F.Fab")
		)
		(pad "1" smd rect
			(at 0 0)
			(size 1.016 0.381)
			(layers "F.Cu" "F.Mask" "F.Paste")
			(net "XDP_CPU_GTL_TCK_R2")
		)
		(pad "2" smd rect
			(at 0 0.649986)
			(size 1.016 0.381)
			(layers "F.Cu" "F.Mask" "F.Paste")
			(net "XDP_CPU_TCK_BUF")
		)
		(pad "3" smd rect
			(at 0 1.299972)
			(size 1.016 0.381)
			(layers "F.Cu" "F.Mask" "F.Paste")
			(net "P3V3")
		)
		(pad "4" smd rect
			(at 1.778 1.299972)
			(size 1.016 0.381)
			(layers "F.Cu" "F.Mask" "F.Paste")
			(net "XDP_CPU_TCK0")
		)
		(pad "5" smd rect
			(at 1.778 0.649986)
			(size 1.016 0.381)
			(layers "F.Cu" "F.Mask" "F.Paste")
			(net "XDP_CPU_TCK_BUF")
		)
		(pad "6" smd rect
			(at 1.778 0)
			(size 1.016 0.381)
			(layers "F.Cu" "F.Mask" "F.Paste")
			(net "XDP_CPU_TCK_BUF")
		)
	)
	(footprint ""
		(layer "F.Cu")
		(at 28.7274 -105.3338 90)
		(property "Reference" "R1C32"
			(at 0 0 90)
			(layer "F.SilkS")
			(hide yes)
			(effects
				(font
					(size 1.27 1.27)
				)
			)
		)
		(property "Value" ""
			(at 0 0 90)
			(layer "F.Fab")
			(effects
				(font
					(size 1.27 1.27)
				)
			)
		)
		(duplicate_pad_numbers_are_jumpers no)
		(fp_poly
			(pts
				(xy -0.2794 -0.1016) (xy 0.2794 -0.1016) (xy 0.2794 0.9906) (xy -0.2794 0.9906)
			)
			(stroke
				(width 0)
				(type default)
			)
			(fill no)
			(layer "F.CrtYd")
		)
		(fp_line
			(start 0.2794 -0.1016)
			(end -0.2794 -0.1016)
			(stroke
				(width 0.1)
				(type default)
			)
			(layer "F.Fab")
		)
		(fp_line
			(start -0.2794 -0.1016)
			(end -0.2794 0.9906)
			(stroke
				(width 0.1)
				(type default)
			)
			(layer "F.Fab")
		)
		(fp_line
			(start 0.2794 0.9906)
			(end 0.2794 -0.1016)
			(stroke
				(width 0.1)
				(type default)
			)
			(layer "F.Fab")
		)
		(fp_line
			(start -0.2794 0.9906)
			(end 0.2794 0.9906)
			(stroke
				(width 0.1)
				(type default)
			)
			(layer "F.Fab")
		)
		(pad "1" smd rect
			(at 0 0 90)
			(size 0.508 0.508)
			(layers "F.Cu" "F.Mask" "F.Paste")
			(net "GND")
		)
		(pad "2" smd rect
			(at 0 0.889 90)
			(size 0.508 0.508)
			(layers "F.Cu" "F.Mask" "F.Paste")
			(net "PD_PIROM_CPU1_ADDR2")
		)
		(zone
			(layer "F.Cu")
			(hatch none 0.5)
			(connect_pads
				(clearance 0)
			)
			(min_thickness 0.25)
			(keepout
				(tracks allowed)
				(vias not_allowed)
				(pads allowed)
				(copperpour not_allowed)
				(footprints allowed)
			)
			(placement
				(enabled no)
				(sheetname "")
			)
			(fill
				(thermal_gap 0.5)
				(thermal_bridge_width 0.5)
				(island_removal_mode 0)
			)
			(polygon
				(pts
					(xy 28.9814 -105.0798) (xy 28.9814 -105.5878) (xy 29.3624 -105.5878) (xy 29.3624 -105.0798)
				)
			)
		)
		(zone
			(layer "F.Cu")
			(hatch none 0.5)
			(connect_pads
				(clearance 0)
			)
			(min_thickness 0.25)
			(keepout
				(tracks not_allowed)
				(vias allowed)
				(pads allowed)
				(copperpour not_allowed)
				(footprints allowed)
			)
			(placement
				(enabled no)
				(sheetname "")
			)
			(fill
				(thermal_gap 0.5)
				(thermal_bridge_width 0.5)
				(island_removal_mode 0)
			)
			(polygon
				(pts
					(xy 29.3624 -105.0798) (xy 29.3624 -105.5878) (xy 28.9814 -105.5878) (xy 28.9814 -105.0798)
				)
			)
		)
	)
	(footprint ""
		(layer "F.Cu")
		(at 323.10324 -131.34086)
		(property "Reference" "R6B1"
			(at 0 0 0)
			(layer "F.SilkS")
			(hide yes)
			(effects
				(font
					(size 1.27 1.27)
				)
			)
		)
		(property "Value" ""
			(at 0 0 0)
			(layer "F.Fab")
			(effects
				(font
					(size 1.27 1.27)
				)
			)
		)
		(duplicate_pad_numbers_are_jumpers no)
		(fp_poly
			(pts
				(xy -0.2794 -0.1016) (xy 0.2794 -0.1016) (xy 0.2794 0.9906) (xy -0.2794 0.9906)
			)
			(stroke
				(width 0)
				(type default)
			)
			(fill no)
			(layer "F.CrtYd")
		)
		(fp_line
			(start -0.2794 -0.1016)
			(end -0.2794 0.9906)
			(stroke
				(width 0.1)
				(type default)
			)
			(layer "F.Fab")
		)
		(fp_line
			(start -0.2794 0.9906)
			(end 0.2794 0.9906)
			(stroke
				(width 0.1)
				(type default)
			)
			(layer "F.Fab")
		)
		(fp_line
			(start 0.2794 -0.1016)
			(end -0.2794 -0.1016)
			(stroke
				(width 0.1)
				(type default)
			)
			(layer "F.Fab")
		)
		(fp_line
			(start 0.2794 0.9906)
			(end 0.2794 -0.1016)
			(stroke
				(width 0.1)
				(type default)
			)
			(layer "F.Fab")
		)
		(pad "1" smd rect
			(at 0 0)
			(size 0.508 0.508)
			(layers "F.Cu" "F.Mask" "F.Paste")
			(net "PVCCIO_CPU0")
		)
		(pad "2" smd rect
			(at 0 0.889)
			(size 0.508 0.508)
			(layers "F.Cu" "F.Mask" "F.Paste")
			(net "SVID_ALERT1_CPU0_R_N")
		)
		(zone
			(layer "F.Cu")
			(hatch none 0.5)
			(connect_pads
				(clearance 0)
			)
			(min_thickness 0.25)
			(keepout
				(tracks allowed)
				(vias not_allowed)
				(pads allowed)
				(copperpour not_allowed)
				(footprints allowed)
			)
			(placement
				(enabled no)
				(sheetname "")
			)
			(fill
				(thermal_gap 0.5)
				(thermal_bridge_width 0.5)
				(island_removal_mode 0)
			)
			(polygon
				(pts
					(xy 322.84924 -131.08686) (xy 323.35724 -131.08686) (xy 323.35724 -130.70586) (xy 322.84924 -130.70586)
				)
			)
		)
		(zone
			(layer "F.Cu")
			(hatch none 0.5)
			(connect_pads
				(clearance 0)
			)
			(min_thickness 0.25)
			(keepout
				(tracks not_allowed)
				(vias allowed)
				(pads allowed)
				(copperpour not_allowed)
				(footprints allowed)
			)
			(placement
				(enabled no)
				(sheetname "")
			)
			(fill
				(thermal_gap 0.5)
				(thermal_bridge_width 0.5)
				(island_removal_mode 0)
			)
			(polygon
				(pts
					(xy 322.84924 -130.70586) (xy 323.35724 -130.70586) (xy 323.35724 -131.08686) (xy 322.84924 -131.08686)
				)
			)
		)
	)
	(footprint ""
		(layer "F.Cu")
		(at 276.352 -69.977)
		(property "Reference" "R6D13"
			(at 0 0 0)
			(layer "F.SilkS")
			(hide yes)
			(effects
				(font
					(size 1.27 1.27)
				)
			)
		)
		(property "Value" ""
			(at 0 0 0)
			(layer "F.Fab")
			(effects
				(font
					(size 1.27 1.27)
				)
			)
		)
		(duplicate_pad_numbers_are_jumpers no)
		(fp_poly
			(pts
				(xy -0.2794 -0.1016) (xy 0.2794 -0.1016) (xy 0.2794 0.9906) (xy -0.2794 0.9906)
			)
			(stroke
				(width 0)
				(type default)
			)
			(fill no)
			(layer "F.CrtYd")
		)
		(fp_line
			(start -0.2794 -0.1016)
			(end -0.2794 0.9906)
			(stroke
				(width 0.1)
				(type default)
			)
			(layer "F.Fab")
		)
		(fp_line
			(start -0.2794 0.9906)
			(end 0.2794 0.9906)
			(stroke
				(width 0.1)
				(type default)
			)
			(layer "F.Fab")
		)
		(fp_line
			(start 0.2794 -0.1016)
			(end -0.2794 -0.1016)
			(stroke
				(width 0.1)
				(type default)
			)
			(layer "F.Fab")
		)
		(fp_line
			(start 0.2794 0.9906)
			(end 0.2794 -0.1016)
			(stroke
				(width 0.1)
				(type default)
			)
			(layer "F.Fab")
		)
		(pad "1" smd rect
			(at 0 0)
			(size 0.508 0.508)
			(layers "F.Cu" "F.Mask" "F.Paste")
			(net "PVCCIO_CPU0")
		)
		(pad "2" smd rect
			(at 0 0.889)
			(size 0.508 0.508)
			(layers "F.Cu" "F.Mask" "F.Paste")
			(net "PU_CPU0_SAFE_MODE_BOOT")
		)
		(zone
			(layer "F.Cu")
			(hatch none 0.5)
			(connect_pads
				(clearance 0)
			)
			(min_thickness 0.25)
			(keepout
				(tracks allowed)
				(vias not_allowed)
				(pads allowed)
				(copperpour not_allowed)
				(footprints allowed)
			)
			(placement
				(enabled no)
				(sheetname "")
			)
			(fill
				(thermal_gap 0.5)
				(thermal_bridge_width 0.5)
				(island_removal_mode 0)
			)
			(polygon
				(pts
					(xy 276.098 -69.723) (xy 276.606 -69.723) (xy 276.606 -69.342) (xy 276.098 -69.342)
				)
			)
		)
		(zone
			(layer "F.Cu")
			(hatch none 0.5)
			(connect_pads
				(clearance 0)
			)
			(min_thickness 0.25)
			(keepout
				(tracks not_allowed)
				(vias allowed)
				(pads allowed)
				(copperpour not_allowed)
				(footprints allowed)
			)
			(placement
				(enabled no)
				(sheetname "")
			)
			(fill
				(thermal_gap 0.5)
				(thermal_bridge_width 0.5)
				(island_removal_mode 0)
			)
			(polygon
				(pts
					(xy 276.098 -69.342) (xy 276.606 -69.342) (xy 276.606 -69.723) (xy 276.098 -69.723)
				)
			)
		)
	)
	(footprint ""
		(layer "F.Cu")
		(at 469.138 -20.6502 -90)
		(property "Reference" "R8F11"
			(at 0 0 270)
			(layer "F.SilkS")
			(hide yes)
			(effects
				(font
					(size 1.27 1.27)
				)
			)
		)
		(property "Value" ""
			(at 0 0 270)
			(layer "F.Fab")
			(effects
				(font
					(size 1.27 1.27)
				)
			)
		)
		(duplicate_pad_numbers_are_jumpers no)
		(fp_rect
			(start 0.2794 0.9906)
			(end -0.2794 -0.1016)
			(stroke
				(width 0)
				(type default)
			)
			(fill no)
			(layer "F.CrtYd")
		)
		(fp_line
			(start -0.2794 0.9906)
			(end 0.2794 0.9906)
			(stroke
				(width 0.1)
				(type default)
			)
			(layer "F.Fab")
		)
		(fp_line
			(start 0.2794 0.9906)
			(end 0.2794 -0.1016)
			(stroke
				(width 0.1)
				(type default)
			)
			(layer "F.Fab")
		)
		(fp_line
			(start -0.2794 -0.1016)
			(end -0.2794 0.9906)
			(stroke
				(width 0.1)
				(type default)
			)
			(layer "F.Fab")
		)
		(fp_line
			(start 0.2794 -0.1016)
			(end -0.2794 -0.1016)
			(stroke
				(width 0.1)
				(type default)
			)
			(layer "F.Fab")
		)
		(pad "1" smd rect
			(at 0 0 270)
			(size 0.508 0.508)
			(layers "F.Cu" "F.Mask" "F.Paste")
			(net "GND")
		)
		(pad "2" smd rect
			(at 0 0.889 270)
			(size 0.508 0.508)
			(layers "F.Cu" "F.Mask" "F.Paste")
			(net "AGND_P3V3_STBY")
		)
		(zone
			(layer "F.Cu")
			(hatch none 0.5)
			(connect_pads
				(clearance 0)
			)
			(min_thickness 0.25)
			(keepout
				(tracks allowed)
				(vias not_allowed)
				(pads allowed)
				(copperpour not_allowed)
				(footprints allowed)
			)
			(placement
				(enabled no)
				(sheetname "")
			)
			(fill
				(thermal_gap 0.5)
				(thermal_bridge_width 0.5)
				(island_removal_mode 0)
			)
			(polygon
				(pts
					(xy 468.503 -20.3962) (xy 468.884 -20.3962) (xy 468.884 -20.9042) (xy 468.503 -20.9042)
				)
			)
		)
		(zone
			(layer "F.Cu")
			(hatch none 0.5)
			(connect_pads
				(clearance 0)
			)
			(min_thickness 0.25)
			(keepout
				(tracks not_allowed)
				(vias allowed)
				(pads allowed)
				(copperpour not_allowed)
				(footprints allowed)
			)
			(placement
				(enabled no)
				(sheetname "")
			)
			(fill
				(thermal_gap 0.5)
				(thermal_bridge_width 0.5)
				(island_removal_mode 0)
			)
			(polygon
				(pts
					(xy 468.503 -20.3962) (xy 468.884 -20.3962) (xy 468.884 -20.9042) (xy 468.503 -20.9042)
				)
			)
		)
	)
	(footprint ""
		(layer "F.Cu")
		(at 192.0748 -74.168 90)
		(property "Reference" "RT25"
			(at 1.01473 0.656336 0)
			(unlocked yes)
			(layer "F.SilkS")
			(effects
				(font
					(size 0.4064 0.254)
					(thickness 0.1524)
				)
			)
		)
		(property "Value" ""
			(at 0 0 90)
			(layer "F.Fab")
			(effects
				(font
					(size 1.27 1.27)
				)
			)
		)
		(duplicate_pad_numbers_are_jumpers no)
		(fp_poly
			(pts
				(xy -0.4953 -0.2032) (xy 0.4953 -0.2032) (xy 0.4953 1.6002) (xy -0.4953 1.6002)
			)
			(stroke
				(width 0)
				(type default)
			)
			(fill no)
			(layer "F.CrtYd")
		)
		(fp_line
			(start 0.4953 -0.2032)
			(end 0.4953 1.6002)
			(stroke
				(width 0.1)
				(type default)
			)
			(layer "F.Fab")
		)
		(fp_line
			(start -0.4953 -0.2032)
			(end 0.4953 -0.2032)
			(stroke
				(width 0.1)
				(type default)
			)
			(layer "F.Fab")
		)
		(fp_line
			(start 0.4953 1.6002)
			(end -0.4953 1.6002)
			(stroke
				(width 0.1)
				(type default)
			)
			(layer "F.Fab")
		)
		(fp_line
			(start -0.4953 1.6002)
			(end -0.4953 -0.2032)
			(stroke
				(width 0.1)
				(type default)
			)
			(layer "F.Fab")
		)
		(pad "1" smd rect
			(at 0 0 90)
			(size 0.762 0.889)
			(layers "F.Cu" "F.Mask" "F.Paste")
			(net "VR_PVCCIN_CPU0_PH3_BOOT")
		)
		(pad "2" smd rect
			(at 0 1.397 90)
			(size 0.762 0.889)
			(layers "F.Cu" "F.Mask" "F.Paste")
			(net "VR_PVCCIN_CPU0_PH3_BOOT_R")
		)
		(zone
			(layer "F.Cu")
			(hatch none 0.5)
			(connect_pads
				(clearance 0)
			)
			(min_thickness 0.25)
			(keepout
				(tracks allowed)
				(vias not_allowed)
				(pads allowed)
				(copperpour not_allowed)
				(footprints allowed)
			)
			(placement
				(enabled no)
				(sheetname "")
			)
			(fill
				(thermal_gap 0.5)
				(thermal_bridge_width 0.5)
				(island_removal_mode 0)
			)
			(polygon
				(pts
					(xy 193.0273 -74.549) (xy 192.5193 -74.549) (xy 192.5193 -73.787) (xy 193.0273 -73.787)
				)
			)
		)
		(zone
			(layer "F.Cu")
			(hatch none 0.5)
			(connect_pads
				(clearance 0)
			)
			(min_thickness 0.25)
			(keepout
				(tracks not_allowed)
				(vias allowed)
				(pads allowed)
				(copperpour not_allowed)
				(footprints allowed)
			)
			(placement
				(enabled no)
				(sheetname "")
			)
			(fill
				(thermal_gap 0.5)
				(thermal_bridge_width 0.5)
				(island_removal_mode 0)
			)
			(polygon
				(pts
					(xy 193.0273 -73.787) (xy 193.0273 -74.549) (xy 192.5193 -74.549) (xy 192.5193 -73.787)
				)
			)
		)
	)
	(footprint ""
		(layer "F.Cu")
		(at 482.6508 -33.909)
		(property "Reference" "R1W24"
			(at -0.8382 -0.67818 0)
			(unlocked yes)
			(layer "F.SilkS")
			(effects
				(font
					(size 0.4064 0.254)
					(thickness 0.1524)
				)
				(justify left)
			)
		)
		(property "Value" ""
			(at 0 0 0)
			(layer "F.Fab")
			(effects
				(font
					(size 1.27 1.27)
				)
			)
		)
		(duplicate_pad_numbers_are_jumpers no)
		(fp_poly
			(pts
				(xy -0.2794 -0.1016) (xy 0.2794 -0.1016) (xy 0.2794 0.9906) (xy -0.2794 0.9906)
			)
			(stroke
				(width 0)
				(type default)
			)
			(fill no)
			(layer "F.CrtYd")
		)
		(fp_line
			(start -0.2794 -0.1016)
			(end -0.2794 0.9906)
			(stroke
				(width 0.1)
				(type default)
			)
			(layer "F.Fab")
		)
		(fp_line
			(start -0.2794 0.9906)
			(end 0.2794 0.9906)
			(stroke
				(width 0.1)
				(type default)
			)
			(layer "F.Fab")
		)
		(fp_line
			(start 0.2794 -0.1016)
			(end -0.2794 -0.1016)
			(stroke
				(width 0.1)
				(type default)
			)
			(layer "F.Fab")
		)
		(fp_line
			(start 0.2794 0.9906)
			(end 0.2794 -0.1016)
			(stroke
				(width 0.1)
				(type default)
			)
			(layer "F.Fab")
		)
		(pad "1" smd rect
			(at 0 0)
			(size 0.508 0.508)
			(layers "F.Cu" "F.Mask" "F.Paste")
			(net "XTAL_CK_MNG_OUT")
		)
		(pad "2" smd rect
			(at 0 0.889)
			(size 0.508 0.508)
			(layers "F.Cu" "F.Mask" "F.Paste")
			(net "XTAL_CK_MNG_OUT_R")
		)
		(zone
			(layer "F.Cu")
			(hatch none 0.5)
			(connect_pads
				(clearance 0)
			)
			(min_thickness 0.25)
			(keepout
				(tracks allowed)
				(vias not_allowed)
				(pads allowed)
				(copperpour not_allowed)
				(footprints allowed)
			)
			(placement
				(enabled no)
				(sheetname "")
			)
			(fill
				(thermal_gap 0.5)
				(thermal_bridge_width 0.5)
				(island_removal_mode 0)
			)
			(polygon
				(pts
					(xy 482.3968 -33.655) (xy 482.9048 -33.655) (xy 482.9048 -33.274) (xy 482.3968 -33.274)
				)
			)
		)
		(zone
			(layer "F.Cu")
			(hatch none 0.5)
			(connect_pads
				(clearance 0)
			)
			(min_thickness 0.25)
			(keepout
				(tracks not_allowed)
				(vias allowed)
				(pads allowed)
				(copperpour not_allowed)
				(footprints allowed)
			)
			(placement
				(enabled no)
				(sheetname "")
			)
			(fill
				(thermal_gap 0.5)
				(thermal_bridge_width 0.5)
				(island_removal_mode 0)
			)
			(polygon
				(pts
					(xy 482.3968 -33.274) (xy 482.9048 -33.274) (xy 482.9048 -33.655) (xy 482.3968 -33.655)
				)
			)
		)
	)
)
